# S9S_MB_2U (Grand Teton) — schematic netlist excerpt (pin names and nets, part order shuffled) for the footprints in the layout excerpt that follows; sources: Cadence DE-HDL packaged netlist, KiCad conversion of 03242023_DA0F0TMBIJ0_F0T_Motherboard_J_brd_V01_OCP.brd

C1905  Q_CAP  0.1UF 25V 10% X7R  pkg 0402  page 217 : A = P3V3_AUX_FPGA_VCCIO0 ; B = GND
R1298  Q_RES  1K 1% EMPTY  pkg 0402LF  page 200 : A = P1V05_PCH_AUX ; B = FM_MFG_MODE

(kicad_pcb
	(version 20260206)
	(generator "pcbnew")
	(generator_version "10.0")
	(general
		(thickness 1.6)
		(legacy_teardrops no)
	)
	(paper "A4")
	(title_block
		(title "03242023_DA0F0TMBIJ0_F0T_Motherboard_J_brd_V01_OCP.brd")
		(comment 1 "Grand Teton / footprints 4666-4667 of 6105")
	)
	(layers
		(0 "F.Cu" signal "TOP")
		(4 "In1.Cu" signal "GND")
		(6 "In2.Cu" signal "IN1")
		(8 "In3.Cu" signal "GND1")
		(10 "In4.Cu" signal "IN2")
		(12 "In5.Cu" signal "GND2")
		(14 "In6.Cu" signal "IN3")
		(16 "In7.Cu" signal "GND3")
		(18 "In8.Cu" signal "VCC")
		(20 "In9.Cu" signal "VCC1")
		(22 "In10.Cu" signal "GND4")
		(24 "In11.Cu" signal "IN4")
		(26 "In12.Cu" signal "GND5")
		(28 "In13.Cu" signal "IN5")
		(30 "In14.Cu" signal "GND6")
		(32 "In15.Cu" signal "IN6")
		(34 "In16.Cu" signal "GND7")
		(2 "B.Cu" signal "BOTTOM")
		(9 "F.Adhes" user "F.Adhesive")
		(11 "B.Adhes" user "B.Adhesive")
		(13 "F.Paste" user "Package Geometry/Pastemask Top")
		(15 "B.Paste" user "Package Geometry/Pastemask Bottom")
		(5 "F.SilkS" user "Ref Des/Silkscreen Top")
		(7 "B.SilkS" user "Ref Des/Silkscreen Bottom")
		(1 "F.Mask" user "Board Geometry/Soldermask Top")
		(3 "B.Mask" user "Board Geometry/Soldermask Bottom")
		(17 "Dwgs.User" user "User.Drawings")
		(19 "Cmts.User" user "User.Comments")
		(21 "Eco1.User" user "User.Eco1")
		(23 "Eco2.User" user "User.Eco2")
		(25 "Edge.Cuts" user "Board Geometry/Outline")
		(27 "Margin" user)
		(31 "F.CrtYd" user "Package Geometry/Place Bound Top")
		(29 "B.CrtYd" user "Package Geometry/Place Bound Bottom")
		(35 "F.Fab" user "Ref Des/Assembly Top")
		(33 "B.Fab" user "Ref Des/Assembly Bottom")
	)
	(footprint ""
		(layer "B.Cu")
		(at 312.443622 -33.010348)
		(property "Reference" "R1298"
			(at 0 0 0)
			(layer "B.SilkS")
			(hide yes)
			(effects
				(font
					(size 1.27 1.27)
				)
				(justify mirror)
			)
		)
		(property "Value" ""
			(at 0 0 0)
			(layer "B.Fab")
			(effects
				(font
					(size 1.27 1.27)
				)
				(justify mirror)
			)
		)
		(duplicate_pad_numbers_are_jumpers no)
		(fp_line
			(start -0.7874 -0.4064)
			(end -0.7874 0.4064)
			(stroke
				(width 0.1524)
				(type default)
			)
			(layer "B.SilkS")
		)
		(fp_line
			(start -0.7874 0.4064)
			(end 0.7874 0.4064)
			(stroke
				(width 0.1524)
				(type default)
			)
			(layer "B.SilkS")
		)
		(fp_line
			(start 0.7874 -0.4064)
			(end -0.7874 -0.4064)
			(stroke
				(width 0.1524)
				(type default)
			)
			(layer "B.SilkS")
		)
		(fp_line
			(start 0.7874 0.4064)
			(end 0.7874 -0.4064)
			(stroke
				(width 0.1524)
				(type default)
			)
			(layer "B.SilkS")
		)
		(fp_line
			(start -0.67945 -0.3048)
			(end -0.67945 0.3048)
			(stroke
				(width 0.1)
				(type default)
			)
			(layer "B.Fab")
		)
		(fp_line
			(start -0.67945 0.3048)
			(end -0.120396 0.3048)
			(stroke
				(width 0.1)
				(type default)
			)
			(layer "B.Fab")
		)
		(fp_line
			(start -0.12065 -0.3048)
			(end -0.67945 -0.3048)
			(stroke
				(width 0.1)
				(type default)
			)
			(layer "B.Fab")
		)
		(fp_line
			(start -0.12065 -0.2794)
			(end -0.12065 -0.3048)
			(stroke
				(width 0.1)
				(type default)
			)
			(layer "B.Fab")
		)
		(fp_line
			(start -0.120396 0.2794)
			(end 0.12065 0.2794)
			(stroke
				(width 0.1)
				(type default)
			)
			(layer "B.Fab")
		)
		(fp_line
			(start -0.120396 0.3048)
			(end -0.120396 0.2794)
			(stroke
				(width 0.1)
				(type default)
			)
			(layer "B.Fab")
		)
		(fp_line
			(start 0.12065 -0.305054)
			(end 0.12065 -0.2794)
			(stroke
				(width 0.1)
				(type default)
			)
			(layer "B.Fab")
		)
		(fp_line
			(start 0.12065 -0.2794)
			(end -0.12065 -0.2794)
			(stroke
				(width 0.1)
				(type default)
			)
			(layer "B.Fab")
		)
		(fp_line
			(start 0.12065 0.2794)
			(end 0.12065 0.3048)
			(stroke
				(width 0.1)
				(type default)
			)
			(layer "B.Fab")
		)
		(fp_line
			(start 0.12065 0.3048)
			(end 0.67945 0.3048)
			(stroke
				(width 0.1)
				(type default)
			)
			(layer "B.Fab")
		)
		(fp_line
			(start 0.67945 -0.305054)
			(end 0.12065 -0.305054)
			(stroke
				(width 0.1)
				(type default)
			)
			(layer "B.Fab")
		)
		(fp_line
			(start 0.67945 0.3048)
			(end 0.67945 -0.305054)
			(stroke
				(width 0.1)
				(type default)
			)
			(layer "B.Fab")
		)
		(pad "1" smd circle
			(at 0.40005 0 180)
			(size 0 0)
			(layers "B.Cu" "B.Mask" "B.Paste")
			(net "P1V05_PCH_AUX")
		)
		(pad "2" smd circle
			(at -0.40005 0 180)
			(size 0 0)
			(layers "B.Cu" "B.Mask" "B.Paste")
			(net "FM_MFG_MODE")
		)
	)
	(footprint ""
		(layer "B.Cu")
		(at 175.355758 -111.375444 180)
		(property "Reference" "C1905"
			(at 0 0 0)
			(layer "B.SilkS")
			(hide yes)
			(effects
				(font
					(size 1.27 1.27)
				)
				(justify mirror)
			)
		)
		(property "Value" ""
			(at 0 0 0)
			(layer "B.Fab")
			(effects
				(font
					(size 1.27 1.27)
				)
				(justify mirror)
			)
		)
		(duplicate_pad_numbers_are_jumpers no)
		(fp_line
			(start 0.69215 0.2921)
			(end 0.69215 -0.2921)
			(stroke
				(width 0.1524)
				(type default)
			)
			(layer "B.SilkS")
		)
		(fp_line
			(start 0.69215 -0.2921)
			(end -0.69215 -0.2921)
			(stroke
				(width 0.1524)
				(type default)
			)
			(layer "B.SilkS")
		)
		(fp_line
			(start -0.69215 0.2921)
			(end 0.69215 0.2921)
			(stroke
				(width 0.1524)
				(type default)
			)
			(layer "B.SilkS")
		)
		(fp_line
			(start -0.69215 -0.2921)
			(end -0.69215 0.2921)
			(stroke
				(width 0.1524)
				(type default)
			)
			(layer "B.SilkS")
		)
		(fp_line
			(start 0.51435 0.2794)
			(end 0.51435 -0.2794)
			(stroke
				(width 0.1)
				(type default)
			)
			(layer "B.Fab")
		)
		(fp_line
			(start 0.51435 -0.2794)
			(end -0.51435 -0.2794)
			(stroke
				(width 0.1)
				(type default)
			)
			(layer "B.Fab")
		)
		(fp_line
			(start -0.51435 0.2794)
			(end 0.51435 0.2794)
			(stroke
				(width 0.1)
				(type default)
			)
			(layer "B.Fab")
		)
		(fp_line
			(start -0.51435 -0.2794)
			(end -0.51435 0.2794)
			(stroke
				(width 0.1)
				(type default)
			)
			(layer "B.Fab")
		)
		(pad "1" smd circle
			(at 0.40005 0)
			(size 0 0)
			(layers "B.Cu" "B.Mask" "B.Paste")
			(net "P3V3_AUX_FPGA_VCCIO0")
		)
		(pad "2" smd circle
			(at -0.40005 0)
			(size 0 0)
			(layers "B.Cu" "B.Mask" "B.Paste")
			(net "GND")
		)
		(zone
			(layer "B.Cu")
			(hatch none 0.5)
			(connect_pads
				(clearance 0)
			)
			(min_thickness 0.25)
			(keepout
				(tracks not_allowed)
				(vias allowed)
				(pads allowed)
				(copperpour not_allowed)
				(footprints allowed)
			)
			(placement
				(enabled no)
				(sheetname "")
			)
			(fill
				(thermal_gap 0.5)
				(thermal_bridge_width 0.5)
				(island_removal_mode 0)
			)
			(polygon
				(pts
					(xy 175.165258 -111.463074) (xy 175.256698 -111.52124) (xy 175.456088 -111.52124) (xy 175.546258 -111.463074)
					(xy 175.546258 -111.287814) (xy 175.456088 -111.229394) (xy 175.256698 -111.229394) (xy 175.165258 -111.28756)
				)
			)
		)
	)
)
